FILE_TYPE = CONNECTIVITY;
{Allegro Design Entry HDL 17.2-2016 S081 (4005846) 1/11/2022}
"PAGE_NUMBER" = 102;
0"NC";
1"M_F_CPU1_SA_CB<7:0>";
2"M_F_CPU1_SA_CA<6:0>";
3"M_F_CPU1_SB_CA<6:0>";
4"M_F_CPU1_SB_CB<7:0>";
5"M_F_CPU1_SA_DQ<31:0>";
6"M_F_CPU1_SB_DQ<31:0>";
7"M_F_CPU1_SA_DQS_DN<9:0>";
8"M_F_CPU1_SA_DQS_DP<9:0>";
9"M_F_CPU1_SB_DQS_DN<9:0>";
10"M_F_CPU1_SB_DQS_DP<9:0>";
11"GND\g";
12"GND\g";
13"P3V3_STBY\g";
14"I3C_SPD_DDRAF_CPU1_SCL";
15"I3C_SPD_DDRF_CPU1_SCL";
16"PWRGD_CHF_CPU1_DIMM";
17"TP_CHF_CPU1_DIMM_RFU_6";
18"I3C_SPD_DDRAF_CPU1_SDA";
19"P3V3_STBY\g";
20"PD_CHF_CPU1_DIMM_SAA";
21"TP_CHF_CPU1_DIMM_RFU_0";
22"M_F_CPU1_SB_RSP<0>";
23"TP_CHF_CPU1_DIMM_RFU_2";
24"M_F_CPU1_SA_RSP<0>";
25"TP_CHF_CPU1_DIMM_RFU_4";
26"TP_CHF_CPU1_DIMM_RFU_3";
27"M_F_CPU1_SA_DQ<14>";
28"M_F_CPU1_SA_DQ<13>";
29"M_F_CPU1_SA_DQ<12>";
30"M_F_CPU1_SA_DQ<11>";
31"M_F_CPU1_SA_DQ<10>";
32"GND\g";
33"P12V_MEM_2\g";
34"GND\g";
35"M_F_CPU1_SA_DQ<20>";
36"M_F_CPU1_SA_DQ<19>";
37"M_F_CPU1_SA_DQ<18>";
38"M_F_CPU1_SB_DQS_DP<9>";
39"M_F_CPU1_SB_DQS_DN<9>";
40"M_F_CPU1_SA_DQS_DP<9>";
41"M_F_CPU1_SA_DQS_DN<9>";
42"M_F_CPU1_SA_DQS_DP<8>";
43"M_F_CPU1_SA_DQS_DN<8>";
44"M_F_CPU1_SB_DQS_DN<7>";
45"M_F_CPU1_SA_DQS_DP<7>";
46"M_F_CPU1_SB_DQS_DP<6>";
47"M_F_CPU1_SB_DQS_DN<6>";
48"M_F_CPU1_SA_DQS_DN<6>";
49"M_F_CPU1_SB_DQS_DP<5>";
50"M_F_CPU1_SB_DQS_DN<5>";
51"M_F_CPU1_SA_DQS_DP<5>";
52"M_F_CPU1_SA_DQS_DN<5>";
53"M_F_CPU1_SB_DQS_DP<4>";
54"M_F_CPU1_SB_DQS_DN<4>";
55"M_F_CPU1_SA_DQS_DP<4>";
56"M_F_CPU1_SA_DQS_DN<4>";
57"M_F_CPU1_SB_DQS_DP<3>";
58"M_F_CPU1_SB_DQS_DN<3>";
59"M_F_CPU1_SA_DQS_DP<3>";
60"M_F_CPU1_SA_DQS_DN<3>";
61"M_F_CPU1_SB_DQS_DP<2>";
62"M_F_CPU1_SB_DQS_DN<2>";
63"M_F_CPU1_SA_DQS_DP<2>";
64"M_F_CPU1_SA_DQS_DN<2>";
65"M_F_CPU1_SB_DQS_DP<1>";
66"M_F_CPU1_SB_DQS_DN<1>";
67"M_F_CPU1_SA_DQS_DP<1>";
68"M_F_CPU1_SA_DQS_DN<1>";
69"M_F_CPU1_SB_DQS_DP<0>";
70"M_F_CPU1_SB_DQS_DN<0>";
71"M_F_CPU1_SA_DQS_DP<0>";
72"M_F_CPU1_SA_DQS_DN<0>";
73"M_F_CPU1_SB_DQS_DP<7>";
74"M_F_CPU1_SB_DQS_DN<8>";
75"M_F_CPU1_SB_DQS_DP<8>";
76"M_F_CPU1_SA_DQS_DP<6>";
77"M_F_CPU1_SA_DQS_DN<7>";
78"TP_CHF_CPU1_DIMM_RFU_1";
79"TP_CHF_CPU1_DIMM_RFU_5";
80"M_F_CPU1_RESET_N";
81"M_F_CPU1_SB_PAR";
82"M_F_CPU1_SA_PAR";
83"M_F_CPU1_SB_DQ<0>";
84"M_F_CPU1_SB_DQ<1>";
85"M_F_CPU1_SB_DQ<2>";
86"M_F_CPU1_SB_DQ<3>";
87"M_F_CPU1_SB_DQ<4>";
88"M_F_CPU1_SB_DQ<5>";
89"M_F_CPU1_SB_DQ<6>";
90"M_F_CPU1_SB_DQ<7>";
91"M_F_CPU1_SB_DQ<8>";
92"M_F_CPU1_SB_DQ<9>";
93"M_F_CPU1_SB_DQ<10>";
94"M_F_CPU1_SB_DQ<11>";
95"M_F_CPU1_SB_DQ<12>";
96"M_F_CPU1_SB_DQ<13>";
97"M_F_CPU1_SB_DQ<14>";
98"M_F_CPU1_SB_DQ<15>";
99"M_F_CPU1_SB_DQ<16>";
100"M_F_CPU1_SB_DQ<17>";
101"M_F_CPU1_SB_DQ<18>";
102"M_F_CPU1_SB_DQ<19>";
103"M_F_CPU1_SB_DQ<20>";
104"M_F_CPU1_SB_DQ<21>";
105"M_F_CPU1_SB_DQ<22>";
106"M_F_CPU1_SB_DQ<23>";
107"M_F_CPU1_SB_DQ<24>";
108"M_F_CPU1_SB_DQ<25>";
109"M_F_CPU1_SB_DQ<26>";
110"M_F_CPU1_SB_DQ<27>";
111"M_F_CPU1_SB_DQ<28>";
112"M_F_CPU1_SB_DQ<29>";
113"M_F_CPU1_SB_DQ<30>";
114"M_F_CPU1_SB_DQ<31>";
115"M_F_CPU1_SA_DQ<0>";
116"M_F_CPU1_SA_DQ<1>";
117"M_F_CPU1_SA_DQ<2>";
118"M_F_CPU1_SA_DQ<3>";
119"M_F_CPU1_SA_DQ<4>";
120"M_F_CPU1_SA_DQ<5>";
121"M_F_CPU1_SA_DQ<6>";
122"M_F_CPU1_SA_DQ<7>";
123"M_F_CPU1_SA_DQ<8>";
124"M_F_CPU1_SA_DQ<9>";
125"M_F_CPU1_SA_DQ<15>";
126"M_F_CPU1_SA_DQ<16>";
127"M_F_CPU1_SA_DQ<17>";
128"M_F_CPU1_SA_DQ<21>";
129"M_F_CPU1_SA_DQ<22>";
130"M_F_CPU1_SA_DQ<23>";
131"M_F_CPU1_SA_DQ<24>";
132"M_F_CPU1_SA_DQ<25>";
133"M_F_CPU1_SA_DQ<26>";
134"M_F_CPU1_SA_DQ<27>";
135"M_F_CPU1_SA_DQ<28>";
136"M_F_CPU1_SA_DQ<29>";
137"M_F_CPU1_SA_DQ<30>";
138"M_F_CPU1_SB_CS_N<1>";
139"M_F_CPU1_SA_CS_N<1>";
140"M_F_CPU1_SB_CS_N<0>";
141"M_F_CPU1_SA_CS_N<0>";
142"M_F_CPU1_CLK_DP<0>";
143"M_F_CPU1_CLK_DN<0>";
144"M_F_CPU1_SB_CB<0>";
145"M_F_CPU1_SB_CB<1>";
146"M_F_CPU1_SB_CB<2>";
147"M_F_CPU1_SB_CB<3>";
148"M_F_CPU1_SB_CB<4>";
149"M_F_CPU1_SB_CB<5>";
150"M_F_CPU1_SB_CB<6>";
151"M_F_CPU1_SA_CB<0>";
152"M_F_CPU1_SA_CB<2>";
153"M_F_CPU1_SA_CB<3>";
154"M_F_CPU1_SA_CB<5>";
155"M_F_CPU1_SA_CB<6>";
156"M_F_CPU1_SB_CA<6>";
157"M_F_CPU1_SA_CA<6>";
158"M_F_CPU1_SB_CA<5>";
159"M_F_CPU1_SA_CA<5>";
160"M_F_CPU1_SB_CA<4>";
161"M_F_CPU1_SA_CA<4>";
162"M_F_CPU1_SB_CA<3>";
163"M_F_CPU1_SA_CA<3>";
164"M_F_CPU1_SB_CA<2>";
165"M_F_CPU1_SA_CA<2>";
166"M_F_CPU1_SB_CA<1>";
167"M_F_CPU1_SA_CA<1>";
168"M_F_CPU1_SB_CA<0>";
169"M_F_CPU1_SA_CA<0>";
170"M_F_CPU1_ALERT_N";
171"M_F_CPU1_SB_CB<7>";
172"M_F_CPU1_SA_CB<1>";
173"M_F_CPU1_SA_CB<4>";
174"M_F_CPU1_SA_CB<7>";
175"M_F_CPU1_SA_DQ<31>";
176"GND\g";
177"PWRGD_CHAF_CPU1";
178"PD_CHF_CPU1_DIMM_SAA";
%"TAP"
"1","(-6125,4325)","0","mstr_standard","I100";
;
CDS_LIB"mstr_standard"
BODY_TYPE"PLUMBING"
HDL_TAP"TRUE";
"B \NAC \NWC"5;
"S \NAC"
BN"7"122;
%"TAP"
"1","(-6125,4275)","0","mstr_standard","I101";
;
CDS_LIB"mstr_standard"
BODY_TYPE"PLUMBING"
HDL_TAP"TRUE";
"B \NAC \NWC"5;
"S \NAC"
BN"6"121;
%"TAP"
"1","(-6125,4375)","0","mstr_standard","I102";
;
CDS_LIB"mstr_standard"
BODY_TYPE"PLUMBING"
HDL_TAP"TRUE";
"B \NAC \NWC"5;
"S \NAC"
BN"8"123;
%"TAP"
"1","(-6125,4425)","0","mstr_standard","I103";
;
CDS_LIB"mstr_standard"
BODY_TYPE"PLUMBING"
HDL_TAP"TRUE";
"B \NAC \NWC"5;
"S \NAC"
BN"9"124;
%"TAP"
"1","(-6125,4525)","0","mstr_standard","I104";
;
CDS_LIB"mstr_standard"
BODY_TYPE"PLUMBING"
HDL_TAP"TRUE";
"B \NAC \NWC"5;
"S \NAC"
BN"11"30;
%"TAP"
"1","(-6125,4575)","0","mstr_standard","I105";
;
CDS_LIB"mstr_standard"
BODY_TYPE"PLUMBING"
HDL_TAP"TRUE";
"B \NAC \NWC"5;
"S \NAC"
BN"12"29;
%"TAP"
"1","(-6125,4625)","0","mstr_standard","I106";
;
CDS_LIB"mstr_standard"
BODY_TYPE"PLUMBING"
HDL_TAP"TRUE";
"B \NAC \NWC"5;
"S \NAC"
BN"13"28;
%"TAP"
"1","(-6125,4675)","0","mstr_standard","I107";
;
CDS_LIB"mstr_standard"
BODY_TYPE"PLUMBING"
HDL_TAP"TRUE";
"B \NAC \NWC"5;
"S \NAC"
BN"14"27;
%"TAP"
"1","(-6125,4475)","0","mstr_standard","I108";
;
CDS_LIB"mstr_standard"
BODY_TYPE"PLUMBING"
HDL_TAP"TRUE";
"B \NAC \NWC"5;
"S \NAC"
BN"10"31;
%"TAP"
"1","(-6125,4925)","0","mstr_standard","I109";
;
CDS_LIB"mstr_standard"
BODY_TYPE"PLUMBING"
HDL_TAP"TRUE";
"B \NAC \NWC"5;
"S \NAC"
BN"19"36;
%"TAP"
"1","(-6125,4775)","0","mstr_standard","I110";
;
CDS_LIB"mstr_standard"
BODY_TYPE"PLUMBING"
HDL_TAP"TRUE";
"B \NAC \NWC"5;
"S \NAC"
BN"16"126;
%"TAP"
"1","(-6125,4875)","0","mstr_standard","I111";
;
CDS_LIB"mstr_standard"
BODY_TYPE"PLUMBING"
HDL_TAP"TRUE";
"B \NAC \NWC"5;
"S \NAC"
BN"18"37;
%"TAP"
"1","(-6125,4825)","0","mstr_standard","I112";
;
CDS_LIB"mstr_standard"
BODY_TYPE"PLUMBING"
HDL_TAP"TRUE";
"B \NAC \NWC"5;
"S \NAC"
BN"17"127;
%"TAP"
"1","(-6125,4725)","0","mstr_standard","I113";
;
CDS_LIB"mstr_standard"
BODY_TYPE"PLUMBING"
HDL_TAP"TRUE";
"B \NAC \NWC"5;
"S \NAC"
BN"15"125;
%"TAP"
"1","(-6125,4975)","0","mstr_standard","I114";
;
CDS_LIB"mstr_standard"
BODY_TYPE"PLUMBING"
HDL_TAP"TRUE";
"B \NAC \NWC"5;
"S \NAC"
BN"20"35;
%"TAP"
"1","(-6125,5025)","0","mstr_standard","I115";
;
CDS_LIB"mstr_standard"
BODY_TYPE"PLUMBING"
HDL_TAP"TRUE";
"B \NAC \NWC"5;
"S \NAC"
BN"21"128;
%"TAP"
"1","(-6125,5075)","0","mstr_standard","I116";
;
CDS_LIB"mstr_standard"
BODY_TYPE"PLUMBING"
HDL_TAP"TRUE";
"B \NAC \NWC"5;
"S \NAC"
BN"22"129;
%"TAP"
"1","(-6125,5225)","0","mstr_standard","I117";
;
CDS_LIB"mstr_standard"
BODY_TYPE"PLUMBING"
HDL_TAP"TRUE";
"B \NAC \NWC"5;
"S \NAC"
BN"25"132;
%"TAP"
"1","(-6125,5125)","0","mstr_standard","I118";
;
CDS_LIB"mstr_standard"
BODY_TYPE"PLUMBING"
HDL_TAP"TRUE";
"B \NAC \NWC"5;
"S \NAC"
BN"23"130;
%"TAP"
"1","(-6125,5175)","0","mstr_standard","I119";
;
CDS_LIB"mstr_standard"
BODY_TYPE"PLUMBING"
HDL_TAP"TRUE";
"B \NAC \NWC"5;
"S \NAC"
BN"24"131;
%"TAP"
"1","(-6125,5425)","0","mstr_standard","I120";
;
CDS_LIB"mstr_standard"
BODY_TYPE"PLUMBING"
HDL_TAP"TRUE";
"B \NAC \NWC"5;
"S \NAC"
BN"29"136;
%"TAP"
"1","(-6125,5475)","0","mstr_standard","I121";
;
CDS_LIB"mstr_standard"
BODY_TYPE"PLUMBING"
HDL_TAP"TRUE";
"B \NAC \NWC"5;
"S \NAC"
BN"30"137;
%"TAP"
"1","(-6125,5375)","0","mstr_standard","I122";
;
CDS_LIB"mstr_standard"
BODY_TYPE"PLUMBING"
HDL_TAP"TRUE";
"B \NAC \NWC"5;
"S \NAC"
BN"28"135;
%"TAP"
"1","(-6125,5325)","0","mstr_standard","I123";
;
CDS_LIB"mstr_standard"
BODY_TYPE"PLUMBING"
HDL_TAP"TRUE";
"B \NAC \NWC"5;
"S \NAC"
BN"27"134;
%"TAP"
"1","(-6125,5275)","0","mstr_standard","I124";
;
CDS_LIB"mstr_standard"
BODY_TYPE"PLUMBING"
HDL_TAP"TRUE";
"B \NAC \NWC"5;
"S \NAC"
BN"26"133;
%"TAP"
"1","(-6125,5525)","0","mstr_standard","I125";
;
CDS_LIB"mstr_standard"
BODY_TYPE"PLUMBING"
HDL_TAP"TRUE";
"B \NAC \NWC"5;
"S \NAC"
BN"31"175;
%"GND"
"1","(-6550,1050)","0","mstr_symbols","I128";
;
SIZE"1B"
CDS_LIB"mstr_symbols"
BOM_COST"MEM"
BODY_TYPE"PLUMBING"
VOLTAGE"0.0"
HDL_POWER"GND";
"A\NAC"11;
%"Q_RES"
"2","(-6550,1275)","0","pure_quanta","I129";
;
LOCATION"R773"
$SEC"1"
CDS_SEC"1"
WATTAGE"1/16W"
MATERIAL"CHIP"
TOLERANCE"1%"
VALUE"84.5K"
PART_NUMBER"CS38452FB05"
PACK_TYPE"0402LF"
CDS_LIB"pure_quanta";
"A"
$PN"1"178;
"B"
$PN"2"11;
%"GND"
"1","(-2200,2000)","0","mstr_symbols","I140";
;
SIZE"1B"
CDS_LIB"mstr_symbols"
BODY_TYPE"PLUMBING"
VOLTAGE"0.0"
HDL_POWER"GND";
"A\NAC"32;
%"GND"
"1","(-400,1775)","0","mstr_symbols","I141";
;
CDS_LIB"mstr_symbols"
SIZE"1B"
BODY_TYPE"PLUMBING"
VOLTAGE"0.0"
HDL_POWER"GND";
"A\NAC"34;
%"SCONN288_DDR506112002KQ"
"3","(-1300,3775)","0","pure_quanta","I142";
;
LOCATION"J33"
$SEC"3"
CDS_SEC"3"
PART_TYPE"SMLF"
VALUE"SCONN288_DDR506112002KQ"
MATERIAL"IO"
PART_NUMBER"DFHST8FS479"
CDS_LMAN_SYM_OUTLINE"-450,1800,450,-1750"
NEEDS_NO_SIZE"TRUE"
CDS_LIB"pure_quanta";
"G3"
$PN"G3"34;
"G2"
$PN"G2"34;
"G1"
$PN"G1"34;
"VSS62"
$PN"141"34;
"VSS61"
$PN"139"34;
"VSS60"
$PN"136"34;
"VSS58"
$PN"132"34;
"VSS104"
$PN"240"32;
"VSS102"
$PN"235"32;
"VSS100"
$PN"230"32;
"VIN_BULK2"
$PN"146"33;
"VIN_BULK1"
$PN"145"33;
"VIN_BULK0"
$PN"1"33;
"VSS126"
$PN"288"32;
"VSS125"
$PN"286"32;
"VSS124"
$PN"284"32;
"VSS123"
$PN"281"32;
"VSS122"
$PN"279"32;
"VSS121"
$PN"277"32;
"VSS120"
$PN"275"32;
"VSS119"
$PN"273"32;
"VSS118"
$PN"270"32;
"VSS117"
$PN"268"32;
"VSS116"
$PN"266"32;
"VSS115"
$PN"264"32;
"VSS114"
$PN"262"32;
"VSS113"
$PN"259"32;
"VSS112"
$PN"257"32;
"VSS111"
$PN"255"32;
"VSS110"
$PN"253"32;
"VSS109"
$PN"251"32;
"VSS108"
$PN"248"32;
"VSS107"
$PN"246"32;
"VSS106"
$PN"244"32;
"VSS105"
$PN"242"32;
"VSS103"
$PN"237"32;
"VSS101"
$PN"233"32;
"VSS99"
$PN"228"32;
"VSS98"
$PN"226"32;
"VSS97"
$PN"224"32;
"VSS96"
$PN"222"32;
"VSS95"
$PN"219"32;
"VSS94"
$PN"216"32;
"VSS93"
$PN"214"32;
"VSS92"
$PN"212"32;
"VSS91"
$PN"210"32;
"VSS90"
$PN"208"32;
"VSS89"
$PN"206"32;
"VSS88"
$PN"204"32;
"VSS87"
$PN"202"32;
"VSS86"
$PN"199"32;
"VSS85"
$PN"197"32;
"VSS84"
$PN"195"32;
"VSS83"
$PN"193"32;
"VSS82"
$PN"191"32;
"VSS81"
$PN"188"32;
"VSS80"
$PN"186"32;
"VSS79"
$PN"184"32;
"VSS78"
$PN"182"32;
"VSS77"
$PN"180"32;
"VSS76"
$PN"177"32;
"VSS75"
$PN"175"32;
"VSS74"
$PN"173"32;
"VSS73"
$PN"171"32;
"VSS72"
$PN"169"32;
"VSS71"
$PN"166"32;
"VSS70"
$PN"164"32;
"VSS69"
$PN"162"32;
"VSS68"
$PN"160"32;
"VSS67"
$PN"158"32;
"VSS66"
$PN"155"32;
"VSS65"
$PN"153"32;
"VSS64"
$PN"151"32;
"VSS63"
$PN"143"34;
"VSS59"
$PN"134"34;
"VSS57"
$PN"130"34;
"VSS56"
$PN"128"34;
"VSS55"
$PN"125"34;
"VSS54"
$PN"123"34;
"VSS53"
$PN"121"34;
"VSS52"
$PN"119"34;
"VSS51"
$PN"117"34;
"VSS50"
$PN"114"34;
"VSS49"
$PN"112"34;
"VSS48"
$PN"110"34;
"VSS47"
$PN"108"34;
"VSS46"
$PN"106"34;
"VSS45"
$PN"103"34;
"VSS44"
$PN"101"34;
"VSS43"
$PN"99"34;
"VSS42"
$PN"97"34;
"VSS41"
$PN"95"34;
"VSS40"
$PN"92"34;
"VSS39"
$PN"90"34;
"VSS38"
$PN"88"34;
"VSS37"
$PN"85"34;
"VSS36"
$PN"83"34;
"VSS35"
$PN"81"34;
"VSS34"
$PN"79"34;
"VSS33"
$PN"77"34;
"VSS32"
$PN"75"34;
"VSS31"
$PN"73"34;
"VSS30"
$PN"71"34;
"VSS29"
$PN"69"34;
"VSS28"
$PN"67"34;
"VSS27"
$PN"65"34;
"VSS26"
$PN"63"34;
"VSS25"
$PN"61"34;
"VSS24"
$PN"59"34;
"VSS23"
$PN"57"34;
"VSS22"
$PN"54"34;
"VSS21"
$PN"52"34;
"VSS20"
$PN"50"34;
"VSS19"
$PN"48"34;
"VSS18"
$PN"46"34;
"VSS17"
$PN"43"34;
"VSS16"
$PN"41"34;
"VSS15"
$PN"39"34;
"VSS14"
$PN"37"34;
"VSS13"
$PN"35"34;
"VSS12"
$PN"32"34;
"VSS11"
$PN"30"34;
"VSS10"
$PN"28"34;
"VSS9"
$PN"26"34;
"VSS8"
$PN"24"34;
"VSS7"
$PN"21"34;
"VSS6"
$PN"19"34;
"VSS5"
$PN"17"34;
"VSS4"
$PN"15"34;
"VSS3"
$PN"13"34;
"VSS2"
$PN"10"34;
"VSS1"
$PN"8"34;
"VSS0"
$PN"6"34;
%"Q_CAP"
"1","(-8675,3350)","2","pure_quanta","I185";
;
LOCATION"C156"
$SEC"1"
CDS_SEC"1"
TOLERANCE"10%"
VALUE"0.1UF"
VOLTAGE"25V"
MATERIAL"X7R"
PACK_TYPE"0402"
PART_NUMBER"CH4104K1B00"
BOM_COST"MEM"
CDS_LIB"pure_quanta"
ROOM"MEM_CH_A_CPU0_DIMM1";
"B"
$PN"2"12;
"A"
$PN"1"19;
%"GND"
"1","(-8675,3125)","0","mstr_symbols","I186";
;
BOM_COST"MEM"
SIZE"1B"
CDS_LIB"mstr_symbols"
BODY_TYPE"PLUMBING"
VOLTAGE"0"
ROOM"MEM_EFGH_DECOUPLING_CAPS"
HDL_POWER"GND";
"A\NAC"12;
%"Q_RES"
"1","(-8600,2275)","2","pure_quanta","I188";
;
LOCATION"R1183"
$SEC"1"
CDS_SEC"1"
VALUE"0"
BOM_COST"MEM"
CDS_LIB"pure_quanta"
WATTAGE"1/16W"
MATERIAL"CHIP"
TOLERANCE"5%"
PART_NUMBER"CS00002JB38"
PACK_TYPE"0402LF"
ROOM"RST_CPU0_PLD_TO_DIMM";
"B"
$PN"2"177;
"A"
$PN"1"16;
%"VCC_CORE"
"1","(-8475,2600)","0","mstr_symbols","I189";
;
HDL_POWER"P3V3_STBY"
CDS_LIB"mstr_symbols"
VOLTAGE"3.3"
ROOM"PVCCINFAON_CPU0_CTRL";
"A"13;
%"Q_RES"
"2","(-8475,2425)","0","pure_quanta","I190";
;
LOCATION"R108"
$SEC"1"
CDS_SEC"1"
WATTAGE"1/16W"
MATERIAL"EMPTY"
TOLERANCE"5%"
VALUE"1K"
PACK_TYPE"0402LF"
CDS_LIB"pure_quanta"
BOM_COST"MEM"
PART_NUMBER"TMP_QCS21002JB34"
ROOM"MEM_CH_A_CPU0_DIMM1";
"A"
$PN"1"13;
"B"
$PN"2"16;
%"TAP"
"1","(-3500,4000)","0","mstr_standard","I191";
;
CDS_LIB"mstr_standard"
BODY_TYPE"PLUMBING"
HDL_TAP"TRUE";
"B \NAC \NWC"8;
"S \NAC"
BN"2"63;
%"TAP"
"1","(-3500,4200)","0","mstr_standard","I193";
;
CDS_LIB"mstr_standard"
BODY_TYPE"PLUMBING"
HDL_TAP"TRUE";
"B \NAC \NWC"8;
"S \NAC"
BN"4"55;
%"TAP"
"1","(-3300,4650)","0","mstr_standard","I198";
;
CDS_LIB"mstr_standard"
BODY_TYPE"PLUMBING"
HDL_TAP"TRUE";
"B \NAC \NWC"7;
"S \NAC"
BN"9"41;
%"TAP"
"1","(-3300,4550)","0","mstr_standard","I199";
;
CDS_LIB"mstr_standard"
BODY_TYPE"PLUMBING"
HDL_TAP"TRUE";
"B \NAC \NWC"7;
"S \NAC"
BN"8"43;
%"TAP"
"1","(-3300,4450)","0","mstr_standard","I200";
;
CDS_LIB"mstr_standard"
BODY_TYPE"PLUMBING"
HDL_TAP"TRUE";
"B \NAC \NWC"7;
"S \NAC"
BN"7"77;
%"TAP"
"1","(-3500,4700)","0","mstr_standard","I201";
;
CDS_LIB"mstr_standard"
BODY_TYPE"PLUMBING"
HDL_TAP"TRUE";
"B \NAC \NWC"8;
"S \NAC"
BN"9"40;
%"TAP"
"1","(-3500,4600)","0","mstr_standard","I202";
;
CDS_LIB"mstr_standard"
BODY_TYPE"PLUMBING"
HDL_TAP"TRUE";
"B \NAC \NWC"8;
"S \NAC"
BN"8"42;
%"TAP"
"1","(-3500,4400)","0","mstr_standard","I203";
;
CDS_LIB"mstr_standard"
BODY_TYPE"PLUMBING"
HDL_TAP"TRUE";
"B \NAC \NWC"8;
"S \NAC"
BN"6"76;
%"TAP"
"1","(-3500,4500)","0","mstr_standard","I204";
;
CDS_LIB"mstr_standard"
BODY_TYPE"PLUMBING"
HDL_TAP"TRUE";
"B \NAC \NWC"8;
"S \NAC"
BN"7"45;
%"TAP"
"1","(-3300,4350)","0","mstr_standard","I205";
;
CDS_LIB"mstr_standard"
BODY_TYPE"PLUMBING"
HDL_TAP"TRUE";
"B \NAC \NWC"7;
"S \NAC"
BN"6"48;
%"TAP"
"1","(-3300,4250)","0","mstr_standard","I206";
;
CDS_LIB"mstr_standard"
BODY_TYPE"PLUMBING"
HDL_TAP"TRUE";
"B \NAC \NWC"7;
"S \NAC"
BN"5"52;
%"TAP"
"1","(-3300,4150)","0","mstr_standard","I207";
;
CDS_LIB"mstr_standard"
BODY_TYPE"PLUMBING"
HDL_TAP"TRUE";
"B \NAC \NWC"7;
"S \NAC"
BN"4"56;
%"TAP"
"1","(-3300,4050)","0","mstr_standard","I208";
;
CDS_LIB"mstr_standard"
BODY_TYPE"PLUMBING"
HDL_TAP"TRUE";
"B \NAC \NWC"7;
"S \NAC"
BN"3"60;
%"TAP"
"1","(-3300,3950)","0","mstr_standard","I209";
;
CDS_LIB"mstr_standard"
BODY_TYPE"PLUMBING"
HDL_TAP"TRUE";
"B \NAC \NWC"7;
"S \NAC"
BN"2"64;
%"TAP"
"1","(-3500,4300)","0","mstr_standard","I210";
;
CDS_LIB"mstr_standard"
BODY_TYPE"PLUMBING"
HDL_TAP"TRUE";
"B \NAC \NWC"8;
"S \NAC"
BN"5"51;
%"TAP"
"1","(-3500,3900)","0","mstr_standard","I211";
;
CDS_LIB"mstr_standard"
BODY_TYPE"PLUMBING"
HDL_TAP"TRUE";
"B \NAC \NWC"8;
"S \NAC"
BN"1"67;
%"TAP"
"1","(-3500,4100)","0","mstr_standard","I212";
;
CDS_LIB"mstr_standard"
BODY_TYPE"PLUMBING"
HDL_TAP"TRUE";
"B \NAC \NWC"8;
"S \NAC"
BN"3"59;
%"TAP"
"1","(-3300,3750)","0","mstr_standard","I213";
;
CDS_LIB"mstr_standard"
BODY_TYPE"PLUMBING"
HDL_TAP"TRUE";
"B \NAC \NWC"7;
"S \NAC"
BN"0"72;
%"TAP"
"1","(-3300,3850)","0","mstr_standard","I214";
;
CDS_LIB"mstr_standard"
BODY_TYPE"PLUMBING"
HDL_TAP"TRUE";
"B \NAC \NWC"7;
"S \NAC"
BN"1"68;
%"TAP"
"1","(-3300,3600)","0","mstr_standard","I215";
;
CDS_LIB"mstr_standard"
BODY_TYPE"PLUMBING"
HDL_TAP"TRUE";
"B \NAC \NWC"9;
"S \NAC"
BN"9"39;
%"TAP"
"1","(-3300,3500)","0","mstr_standard","I216";
;
CDS_LIB"mstr_standard"
BODY_TYPE"PLUMBING"
HDL_TAP"TRUE";
"B \NAC \NWC"9;
"S \NAC"
BN"8"74;
%"TAP"
"1","(-3300,3400)","0","mstr_standard","I217";
;
CDS_LIB"mstr_standard"
BODY_TYPE"PLUMBING"
HDL_TAP"TRUE";
"B \NAC \NWC"9;
"S \NAC"
BN"7"44;
%"TAP"
"1","(-3500,3650)","0","mstr_standard","I218";
;
CDS_LIB"mstr_standard"
BODY_TYPE"PLUMBING"
HDL_TAP"TRUE";
"B \NAC \NWC"10;
"S \NAC"
BN"9"38;
%"TAP"
"1","(-3500,3800)","0","mstr_standard","I219";
;
CDS_LIB"mstr_standard"
BODY_TYPE"PLUMBING"
HDL_TAP"TRUE";
"B \NAC \NWC"8;
"S \NAC"
BN"0"71;
%"SCONN288_DDR506112002KQ"
"1","(-6975,3775)","0","pure_quanta","I22";
;
LOCATION"J33"
$SEC"1"
CDS_SEC"1"
PART_TYPE"SMLF"
VALUE"SCONN288_DDR506112002KQ"
MATERIAL"IO"
PART_NUMBER"DFHST8FS479"
CDS_LMAN_SYM_OUTLINE"-450,1900,450,-1850"
NEEDS_NO_SIZE"TRUE"
CDS_LIB"pure_quanta";
"PWR_GOOD||FAIL_N"
$PN"147"16;
"DQ31_A"
$PN"194"175;
"CB7_A"
$PN"205"174;
"CB4_A"
$PN"58"173;
"CB1_A"
$PN"53"172;
"CB7_B"
$PN"236"171;
"ALERT_N \B"
$PN"62"170;
"CA0_A"
$PN"66"169;
"CA0_B"
$PN"76"168;
"CA1_A"
$PN"211"167;
"CA1_B"
$PN"221"166;
"CA2_A"
$PN"68"165;
"CA2_B"
$PN"78"164;
"CA3_A"
$PN"213"163;
"CA3_B"
$PN"223"162;
"CA4_A"
$PN"70"161;
"CA4_B"
$PN"80"160;
"CA5_A"
$PN"215"159;
"CA5_B"
$PN"225"158;
"CA6_A"
$PN"72"157;
"CA6_B"
$PN"82"156;
"CB6_A"
$PN"203"155;
"CB5_A"
$PN"60"154;
"CB3_A"
$PN"198"153;
"CB2_A"
$PN"196"152;
"CB0_A"
$PN"51"151;
"CB6_B"
$PN"234"150;
"CB5_B"
$PN"91"149;
"CB4_B"
$PN"89"148;
"CB3_B"
$PN"243"147;
"CB2_B"
$PN"241"146;
"CB1_B"
$PN"98"145;
"CB0_B"
$PN"96"144;
"CK_C \B"
$PN"218"143;
"CK_T"
$PN"217"142;
"CS0_A_N"
$PN"64"141;
"CS0_B_N"
$PN"84"140;
"CS1_A_N"
$PN"209"139;
"CS1_B_N"
$PN"229"138;
"DQ30_A"
$PN"192"137;
"DQ29_A"
$PN"49"136;
"DQ28_A"
$PN"47"135;
"DQ27_A"
$PN"187"134;
"DQ26_A"
$PN"185"133;
"DQ25_A"
$PN"42"132;
"DQ24_A"
$PN"40"131;
"DQ23_A"
$PN"183"130;
"DQ22_A"
$PN"181"129;
"DQ21_A"
$PN"38"128;
"DQ20_A"
$PN"36"35;
"DQ19_A"
$PN"176"36;
"DQ18_A"
$PN"174"37;
"DQ17_A"
$PN"31"127;
"DQ16_A"
$PN"29"126;
"DQ15_A"
$PN"172"125;
"DQ14_A"
$PN"170"27;
"DQ13_A"
$PN"27"28;
"DQ12_A"
$PN"25"29;
"DQ11_A"
$PN"165"30;
"DQ10_A"
$PN"163"31;
"DQ9_A"
$PN"20"124;
"DQ8_A"
$PN"18"123;
"DQ7_A"
$PN"161"122;
"DQ6_A"
$PN"159"121;
"DQ5_A"
$PN"16"120;
"DQ4_A"
$PN"14"119;
"DQ3_A"
$PN"154"118;
"DQ2_A"
$PN"152"117;
"DQ1_A"
$PN"9"116;
"DQ0_A"
$PN"7"115;
"DQ31_B"
$PN"287"114;
"DQ30_B"
$PN"285"113;
"DQ29_B"
$PN"142"112;
"DQ28_B"
$PN"140"111;
"DQ27_B"
$PN"280"110;
"DQ26_B"
$PN"278"109;
"DQ25_B"
$PN"135"108;
"DQ24_B"
$PN"133"107;
"DQ23_B"
$PN"276"106;
"DQ22_B"
$PN"274"105;
"DQ21_B"
$PN"131"104;
"DQ20_B"
$PN"129"103;
"DQ19_B"
$PN"269"102;
"DQ18_B"
$PN"267"101;
"DQ17_B"
$PN"124"100;
"DQ16_B"
$PN"122"99;
"DQ15_B"
$PN"265"98;
"DQ14_B"
$PN"263"97;
"DQ13_B"
$PN"120"96;
"DQ12_B"
$PN"118"95;
"DQ11_B"
$PN"258"94;
"DQ10_B"
$PN"256"93;
"DQ9_B"
$PN"113"92;
"DQ8_B"
$PN"111"91;
"DQ7_B"
$PN"254"90;
"DQ6_B"
$PN"252"89;
"DQ5_B"
$PN"109"88;
"DQ4_B"
$PN"107"87;
"DQ3_B"
$PN"247"86;
"DQ2_B"
$PN"245"85;
"DQ1_B"
$PN"102"84;
"DQ0_B"
$PN"100"83;
"HAS"
$PN"148"20;
"HSCL"
$PN"4"15;
"HSDA"
$PN"5"18;
"LBD||RSP_A_N"
$PN"86"24;
"LBS||RSP_B_N"
$PN"87"22;
"PAR_A"
$PN"74"82;
"PAR_B"
$PN"227"81;
"RESET_N \B"
$PN"207"80;
"RFU6"
$PN"232"17;
"RFU5"
$PN"231"79;
"RFU4"
$PN"220"25;
"RFU3"
$PN"150"26;
"RFU2"
$PN"149"23;
"RFU1"
$PN"144"78;
"RFU0"
$PN"2"21;
"VIN_MGMT"
$PN"3"19;
%"TAP"
"1","(-3500,3550)","0","mstr_standard","I220";
;
CDS_LIB"mstr_standard"
BODY_TYPE"PLUMBING"
HDL_TAP"TRUE";
"B \NAC \NWC"10;
"S \NAC"
BN"8"75;
%"TAP"
"1","(-3500,3450)","0","mstr_standard","I221";
;
CDS_LIB"mstr_standard"
BODY_TYPE"PLUMBING"
HDL_TAP"TRUE";
"B \NAC \NWC"10;
"S \NAC"
BN"7"73;
%"TAP"
"1","(-3300,3300)","0","mstr_standard","I222";
;
CDS_LIB"mstr_standard"
BODY_TYPE"PLUMBING"
HDL_TAP"TRUE";
"B \NAC \NWC"9;
"S \NAC"
BN"6"47;
%"TAP"
"1","(-3300,3200)","0","mstr_standard","I223";
;
CDS_LIB"mstr_standard"
BODY_TYPE"PLUMBING"
HDL_TAP"TRUE";
"B \NAC \NWC"9;
"S \NAC"
BN"5"50;
%"TAP"
"1","(-3300,3000)","0","mstr_standard","I224";
;
CDS_LIB"mstr_standard"
BODY_TYPE"PLUMBING"
HDL_TAP"TRUE";
"B \NAC \NWC"9;
"S \NAC"
BN"3"58;
%"TAP"
"1","(-3300,3100)","0","mstr_standard","I225";
;
CDS_LIB"mstr_standard"
BODY_TYPE"PLUMBING"
HDL_TAP"TRUE";
"B \NAC \NWC"9;
"S \NAC"
BN"4"54;
%"TAP"
"1","(-3300,2900)","0","mstr_standard","I226";
;
CDS_LIB"mstr_standard"
BODY_TYPE"PLUMBING"
HDL_TAP"TRUE";
"B \NAC \NWC"9;
"S \NAC"
BN"2"62;
%"TAP"
"1","(-3500,3150)","0","mstr_standard","I227";
;
CDS_LIB"mstr_standard"
BODY_TYPE"PLUMBING"
HDL_TAP"TRUE";
"B \NAC \NWC"10;
"S \NAC"
BN"4"53;
%"TAP"
"1","(-3500,3350)","0","mstr_standard","I228";
;
CDS_LIB"mstr_standard"
BODY_TYPE"PLUMBING"
HDL_TAP"TRUE";
"B \NAC \NWC"10;
"S \NAC"
BN"6"46;
%"TAP"
"1","(-3500,3250)","0","mstr_standard","I229";
;
CDS_LIB"mstr_standard"
BODY_TYPE"PLUMBING"
HDL_TAP"TRUE";
"B \NAC \NWC"10;
"S \NAC"
BN"5"49;
%"TAP"
"1","(-7825,3325)","2","mstr_standard","I23";
;
CDS_LIB"mstr_standard"
BODY_TYPE"PLUMBING"
HDL_TAP"TRUE";
"B \NAC \NWC"4;
"S \NAC"
BN"0"144;
%"TAP"
"1","(-3500,2950)","0","mstr_standard","I230";
;
CDS_LIB"mstr_standard"
BODY_TYPE"PLUMBING"
HDL_TAP"TRUE";
"B \NAC \NWC"10;
"S \NAC"
BN"2"61;
%"TAP"
"1","(-3500,3050)","0","mstr_standard","I231";
;
CDS_LIB"mstr_standard"
BODY_TYPE"PLUMBING"
HDL_TAP"TRUE";
"B \NAC \NWC"10;
"S \NAC"
BN"3"57;
%"TAP"
"1","(-3300,2800)","0","mstr_standard","I232";
;
CDS_LIB"mstr_standard"
BODY_TYPE"PLUMBING"
HDL_TAP"TRUE";
"B \NAC \NWC"9;
"S \NAC"
BN"1"66;
%"TAP"
"1","(-3300,2700)","0","mstr_standard","I233";
;
CDS_LIB"mstr_standard"
BODY_TYPE"PLUMBING"
HDL_TAP"TRUE";
"B \NAC \NWC"9;
"S \NAC"
BN"0"70;
%"TAP"
"1","(-3500,2750)","0","mstr_standard","I234";
;
CDS_LIB"mstr_standard"
BODY_TYPE"PLUMBING"
HDL_TAP"TRUE";
"B \NAC \NWC"10;
"S \NAC"
BN"0"69;
%"TAP"
"1","(-3500,2850)","0","mstr_standard","I235";
;
CDS_LIB"mstr_standard"
BODY_TYPE"PLUMBING"
HDL_TAP"TRUE";
"B \NAC \NWC"10;
"S \NAC"
BN"1"65;
%"SCONN288_DDR506112002KQ"
"2","(-4450,3700)","0","pure_quanta","I236";
;
LOCATION"J33"
$SEC"2"
CDS_SEC"2"
VALUE"SCONN288_DDR506112002KQ"
MATERIAL"IO"
PART_TYPE"SMLF"
PART_NUMBER"DFHST8FS479"
CDS_LMAN_SYM_OUTLINE"-600,1150,600,-1150"
NEEDS_NO_SIZE"TRUE"
CDS_LIB"pure_quanta";
"DQS7_A_C||TDQS7_A_C \B"
$PN"178"77;
"DQS6_A_T||TDQS6_A_T"
$PN"168"76;
"DQS8_B_T||TDQS8_B_T"
$PN"283"75;
"DQS8_B_C||TDQS8_B_C \B"
$PN"282"74;
"DQS7_B_T||TDQS7_B_T"
$PN"272"73;
"DQS0_A_C \B"
$PN"12"72;
"DQS0_A_T"
$PN"11"71;
"DQS0_B_C \B"
$PN"105"70;
"DQS0_B_T"
$PN"104"69;
"DQS1_A_C \B"
$PN"23"68;
"DQS1_A_T"
$PN"22"67;
"DQS1_B_C \B"
$PN"116"66;
"DQS1_B_T"
$PN"115"65;
"DQS2_A_C \B"
$PN"34"64;
"DQS2_A_T"
$PN"33"63;
"DQS2_B_C \B"
$PN"127"62;
"DQS2_B_T"
$PN"126"61;
"DQS3_A_C \B"
$PN"45"60;
"DQS3_A_T"
$PN"44"59;
"DQS3_B_C \B"
$PN"138"58;
"DQS3_B_T"
$PN"137"57;
"DQS4_A_C \B"
$PN"56"56;
"DQS4_A_T"
$PN"55"55;
"DQS4_B_C \B"
$PN"238"54;
"DQS4_B_T"
$PN"239"53;
"DQS5_A_C||TDQS5_A_C||DQS5_A_T||TDQS5_A_T \B"
$PN"156"52;
"DQS5_A_T||TDQS5_A_T"
$PN"157"51;
"DQS5_B_C||TDQS5_B_C \B"
$PN"249"50;
"DQS5_B_T||TDQS5_B_T"
$PN"250"49;
"DQS6_A_C||TDQS6_A_C||DQS6_A_T||TDQS6_A_T \B"
$PN"167"48;
"DQS6_B_C||TDQS6_B_C \B"
$PN"260"47;
"DQS6_B_T||TDQS6_B_T"
$PN"261"46;
"DQS7_A_T||TDQS7_A_T"
$PN"179"45;
"DQS7_B_C||TDQS7_B_C \B"
$PN"271"44;
"DQS8_A_C||TDQS8_A_C \B"
$PN"189"43;
"DQS8_A_T||TDQS8_A_T"
$PN"190"42;
"DQS9_A_C||TDQS9_A_C \B"
$PN"200"41;
"DQS9_A_T||TDQS9_A_T"
$PN"201"40;
"DQS9_B_C||TDQS9_B_C \B"
$PN"94"39;
"DQS9_B_T||TDQS9_B_T||DBI4_B_N"
$PN"93"38;
%"GND"
"1","(-2900,5650)","0","pure_quanta_power","I237";
;
CDS_LIB"pure_quanta_power"
BOM_COST"MEM"
SIZE"1B"
ROOM"MEM_EFGH_DECOUPLING_CAPS"
HDL_POWER"GND";
"A<SIZE-1..0>\NAC"176;
%"Q_CAP"
"1","(-2900,6000)","2","pure_quanta","I238";
;
LOCATION"C518"
$SEC"1"
CDS_SEC"1"
MATERIAL"X6S"
TOLERANCE"10%"
VALUE"10UF"
VOLTAGE"25V"
PACK_TYPE"C0805"
PART_NUMBER"CH6104KEA00"
BOM_COST"MEM"
CDS_LIB"pure_quanta"
ROOM"MEM_CH_A_CPU0_DIMM1";
"B"
$PN"2"176;
"A"
$PN"1"33;
%"Q_CAP"
"1","(-2325,6000)","2","pure_quanta","I239";
;
LOCATION"C527"
$SEC"1"
CDS_SEC"1"
MATERIAL"X6S"
TOLERANCE"10%"
VALUE"10UF"
PART_NUMBER"CH6104KEA00"
VOLTAGE"25V"
PACK_TYPE"C0805"
BOM_COST"MEM"
CDS_LIB"pure_quanta"
ROOM"MEM_CH_A_CPU0_DIMM1";
"B"
$PN"2"176;
"A"
$PN"1"33;
%"TAP"
"1","(-7825,3375)","2","mstr_standard","I24";
;
CDS_LIB"mstr_standard"
BODY_TYPE"PLUMBING"
HDL_TAP"TRUE";
"B \NAC \NWC"4;
"S \NAC"
BN"1"145;
%"UNIVERSAL_POWER"
"1","(-2900,6325)","0","pure_quanta_power","I240";
;
HDL_POWER"P12V_MEM_2"
CDS_LIB"pure_quanta_power";
"A"33;
%"Q_RES"
"1","(-7875,2825)","0","pure_quanta","I242";
;
$LOCATION"R1585"
CDS_LOCATION"R1585"
$SEC"1"
CDS_SEC"1"
VALUE"49.9"
CDS_LIB"pure_quanta"
MATERIAL"CHIP"
PACK_TYPE"0402LF"
WATTAGE"1/16W"
TOLERANCE"1%"
PART_NUMBER"CS04992FB07";
"B"
$PN"2"15;
"A"
$PN"1"14;
%"TAP"
"1","(-7825,3425)","2","mstr_standard","I25";
;
CDS_LIB"mstr_standard"
BODY_TYPE"PLUMBING"
HDL_TAP"TRUE";
"B \NAC \NWC"4;
"S \NAC"
BN"2"146;
%"TAP"
"1","(-7825,3475)","2","mstr_standard","I26";
;
CDS_LIB"mstr_standard"
BODY_TYPE"PLUMBING"
HDL_TAP"TRUE";
"B \NAC \NWC"4;
"S \NAC"
BN"3"147;
%"TAP"
"1","(-7825,3525)","2","mstr_standard","I27";
;
CDS_LIB"mstr_standard"
BODY_TYPE"PLUMBING"
HDL_TAP"TRUE";
"B \NAC \NWC"4;
"S \NAC"
BN"4"148;
%"TAP"
"1","(-7825,3625)","2","mstr_standard","I28";
;
CDS_LIB"mstr_standard"
BODY_TYPE"PLUMBING"
HDL_TAP"TRUE";
"B \NAC \NWC"4;
"S \NAC"
BN"6"150;
%"TAP"
"1","(-7825,3575)","2","mstr_standard","I29";
;
CDS_LIB"mstr_standard"
BODY_TYPE"PLUMBING"
HDL_TAP"TRUE";
"B \NAC \NWC"4;
"S \NAC"
BN"5"149;
%"TAP"
"1","(-7825,3675)","2","mstr_standard","I30";
;
CDS_LIB"mstr_standard"
BODY_TYPE"PLUMBING"
HDL_TAP"TRUE";
"B \NAC \NWC"4;
"S \NAC"
BN"7"171;
%"TAP"
"1","(-7825,3775)","2","mstr_standard","I31";
;
CDS_LIB"mstr_standard"
BODY_TYPE"PLUMBING"
HDL_TAP"TRUE";
"B \NAC \NWC"1;
"S \NAC"
BN"0"151;
%"TAP"
"1","(-7825,3825)","2","mstr_standard","I32";
;
CDS_LIB"mstr_standard"
BODY_TYPE"PLUMBING"
HDL_TAP"TRUE";
"B \NAC \NWC"1;
"S \NAC"
BN"1"172;
%"TAP"
"1","(-7825,3875)","2","mstr_standard","I33";
;
CDS_LIB"mstr_standard"
BODY_TYPE"PLUMBING"
HDL_TAP"TRUE";
"B \NAC \NWC"1;
"S \NAC"
BN"2"152;
%"TAP"
"1","(-7825,3925)","2","mstr_standard","I34";
;
CDS_LIB"mstr_standard"
BODY_TYPE"PLUMBING"
HDL_TAP"TRUE";
"B \NAC \NWC"1;
"S \NAC"
BN"3"153;
%"TAP"
"1","(-6125,2325)","0","mstr_standard","I35";
;
CDS_LIB"mstr_standard"
BODY_TYPE"PLUMBING"
HDL_TAP"TRUE";
"B \NAC \NWC"6;
"S \NAC"
BN"0"83;
%"TAP"
"1","(-6125,2375)","0","mstr_standard","I36";
;
CDS_LIB"mstr_standard"
BODY_TYPE"PLUMBING"
HDL_TAP"TRUE";
"B \NAC \NWC"6;
"S \NAC"
BN"1"84;
%"TAP"
"1","(-6125,2425)","0","mstr_standard","I37";
;
CDS_LIB"mstr_standard"
BODY_TYPE"PLUMBING"
HDL_TAP"TRUE";
"B \NAC \NWC"6;
"S \NAC"
BN"2"85;
%"TAP"
"1","(-6125,2475)","0","mstr_standard","I38";
;
CDS_LIB"mstr_standard"
BODY_TYPE"PLUMBING"
HDL_TAP"TRUE";
"B \NAC \NWC"6;
"S \NAC"
BN"3"86;
%"TAP"
"1","(-6125,2525)","0","mstr_standard","I39";
;
CDS_LIB"mstr_standard"
BODY_TYPE"PLUMBING"
HDL_TAP"TRUE";
"B \NAC \NWC"6;
"S \NAC"
BN"4"87;
%"TAP"
"1","(-6125,2575)","0","mstr_standard","I40";
;
CDS_LIB"mstr_standard"
BODY_TYPE"PLUMBING"
HDL_TAP"TRUE";
"B \NAC \NWC"6;
"S \NAC"
BN"5"88;
%"TAP"
"1","(-6125,2625)","0","mstr_standard","I41";
;
CDS_LIB"mstr_standard"
BODY_TYPE"PLUMBING"
HDL_TAP"TRUE";
"B \NAC \NWC"6;
"S \NAC"
BN"6"89;
%"TAP"
"1","(-6125,2675)","0","mstr_standard","I42";
;
CDS_LIB"mstr_standard"
BODY_TYPE"PLUMBING"
HDL_TAP"TRUE";
"B \NAC \NWC"6;
"S \NAC"
BN"7"90;
%"TAP"
"1","(-6125,2725)","0","mstr_standard","I43";
;
CDS_LIB"mstr_standard"
BODY_TYPE"PLUMBING"
HDL_TAP"TRUE";
"B \NAC \NWC"6;
"S \NAC"
BN"8"91;
%"TAP"
"1","(-6125,2775)","0","mstr_standard","I44";
;
CDS_LIB"mstr_standard"
BODY_TYPE"PLUMBING"
HDL_TAP"TRUE";
"B \NAC \NWC"6;
"S \NAC"
BN"9"92;
%"TAP"
"1","(-6125,2825)","0","mstr_standard","I45";
;
CDS_LIB"mstr_standard"
BODY_TYPE"PLUMBING"
HDL_TAP"TRUE";
"B \NAC \NWC"6;
"S \NAC"
BN"10"93;
%"TAP"
"1","(-6125,2875)","0","mstr_standard","I46";
;
CDS_LIB"mstr_standard"
BODY_TYPE"PLUMBING"
HDL_TAP"TRUE";
"B \NAC \NWC"6;
"S \NAC"
BN"11"94;
%"TAP"
"1","(-6125,2925)","0","mstr_standard","I47";
;
CDS_LIB"mstr_standard"
BODY_TYPE"PLUMBING"
HDL_TAP"TRUE";
"B \NAC \NWC"6;
"S \NAC"
BN"12"95;
%"TAP"
"1","(-6125,2975)","0","mstr_standard","I48";
;
CDS_LIB"mstr_standard"
BODY_TYPE"PLUMBING"
HDL_TAP"TRUE";
"B \NAC \NWC"6;
"S \NAC"
BN"13"96;
%"TAP"
"1","(-6125,3025)","0","mstr_standard","I49";
;
CDS_LIB"mstr_standard"
BODY_TYPE"PLUMBING"
HDL_TAP"TRUE";
"B \NAC \NWC"6;
"S \NAC"
BN"14"97;
%"VCC_CORE"
"1","(-8575,3550)","0","mstr_symbols","I5";
;
HDL_POWER"P3V3_STBY"
CDS_LIB"mstr_symbols"
VOLTAGE"3.3"
ROOM"PVCCINFAON_CPU1_CTRL";
"A"19;
%"TAP"
"1","(-6125,3125)","0","mstr_standard","I50";
;
CDS_LIB"mstr_standard"
BODY_TYPE"PLUMBING"
HDL_TAP"TRUE";
"B \NAC \NWC"6;
"S \NAC"
BN"16"99;
%"TAP"
"1","(-6125,3075)","0","mstr_standard","I51";
;
CDS_LIB"mstr_standard"
BODY_TYPE"PLUMBING"
HDL_TAP"TRUE";
"B \NAC \NWC"6;
"S \NAC"
BN"15"98;
%"TAP"
"1","(-6125,3175)","0","mstr_standard","I52";
;
CDS_LIB"mstr_standard"
BODY_TYPE"PLUMBING"
HDL_TAP"TRUE";
"B \NAC \NWC"6;
"S \NAC"
BN"17"100;
%"TAP"
"1","(-6125,3275)","0","mstr_standard","I53";
;
CDS_LIB"mstr_standard"
BODY_TYPE"PLUMBING"
HDL_TAP"TRUE";
"B \NAC \NWC"6;
"S \NAC"
BN"19"102;
%"TAP"
"1","(-6125,3325)","0","mstr_standard","I54";
;
CDS_LIB"mstr_standard"
BODY_TYPE"PLUMBING"
HDL_TAP"TRUE";
"B \NAC \NWC"6;
"S \NAC"
BN"20"103;
%"TAP"
"1","(-6125,3425)","0","mstr_standard","I55";
;
CDS_LIB"mstr_standard"
BODY_TYPE"PLUMBING"
HDL_TAP"TRUE";
"B \NAC \NWC"6;
"S \NAC"
BN"22"105;
%"TAP"
"1","(-6125,3375)","0","mstr_standard","I56";
;
CDS_LIB"mstr_standard"
BODY_TYPE"PLUMBING"
HDL_TAP"TRUE";
"B \NAC \NWC"6;
"S \NAC"
BN"21"104;
%"TAP"
"1","(-6125,3225)","0","mstr_standard","I57";
;
CDS_LIB"mstr_standard"
BODY_TYPE"PLUMBING"
HDL_TAP"TRUE";
"B \NAC \NWC"6;
"S \NAC"
BN"18"101;
%"TAP"
"1","(-6125,3525)","0","mstr_standard","I58";
;
CDS_LIB"mstr_standard"
BODY_TYPE"PLUMBING"
HDL_TAP"TRUE";
"B \NAC \NWC"6;
"S \NAC"
BN"24"107;
%"TAP"
"1","(-6125,3575)","0","mstr_standard","I59";
;
CDS_LIB"mstr_standard"
BODY_TYPE"PLUMBING"
HDL_TAP"TRUE";
"B \NAC \NWC"6;
"S \NAC"
BN"25"108;
%"TAP"
"1","(-6125,3675)","0","mstr_standard","I60";
;
CDS_LIB"mstr_standard"
BODY_TYPE"PLUMBING"
HDL_TAP"TRUE";
"B \NAC \NWC"6;
"S \NAC"
BN"27"110;
%"TAP"
"1","(-6125,3625)","0","mstr_standard","I61";
;
CDS_LIB"mstr_standard"
BODY_TYPE"PLUMBING"
HDL_TAP"TRUE";
"B \NAC \NWC"6;
"S \NAC"
BN"26"109;
%"TAP"
"1","(-6125,3475)","0","mstr_standard","I62";
;
CDS_LIB"mstr_standard"
BODY_TYPE"PLUMBING"
HDL_TAP"TRUE";
"B \NAC \NWC"6;
"S \NAC"
BN"23"106;
%"TAP"
"1","(-6125,3775)","0","mstr_standard","I63";
;
CDS_LIB"mstr_standard"
BODY_TYPE"PLUMBING"
HDL_TAP"TRUE";
"B \NAC \NWC"6;
"S \NAC"
BN"29"112;
%"TAP"
"1","(-6125,3875)","0","mstr_standard","I64";
;
CDS_LIB"mstr_standard"
BODY_TYPE"PLUMBING"
HDL_TAP"TRUE";
"B \NAC \NWC"6;
"S \NAC"
BN"31"114;
%"TAP"
"1","(-6125,3825)","0","mstr_standard","I65";
;
CDS_LIB"mstr_standard"
BODY_TYPE"PLUMBING"
HDL_TAP"TRUE";
"B \NAC \NWC"6;
"S \NAC"
BN"30"113;
%"TAP"
"1","(-6125,3725)","0","mstr_standard","I66";
;
CDS_LIB"mstr_standard"
BODY_TYPE"PLUMBING"
HDL_TAP"TRUE";
"B \NAC \NWC"6;
"S \NAC"
BN"28"111;
%"TAP"
"1","(-7825,3975)","2","mstr_standard","I76";
;
CDS_LIB"mstr_standard"
BODY_TYPE"PLUMBING"
HDL_TAP"TRUE";
"B \NAC \NWC"1;
"S \NAC"
BN"4"173;
%"TAP"
"1","(-7825,4025)","2","mstr_standard","I77";
;
CDS_LIB"mstr_standard"
BODY_TYPE"PLUMBING"
HDL_TAP"TRUE";
"B \NAC \NWC"1;
"S \NAC"
BN"5"154;
%"TAP"
"1","(-7825,4125)","2","mstr_standard","I78";
;
CDS_LIB"mstr_standard"
BODY_TYPE"PLUMBING"
HDL_TAP"TRUE";
"B \NAC \NWC"1;
"S \NAC"
BN"7"174;
%"TAP"
"1","(-7825,4075)","2","mstr_standard","I79";
;
CDS_LIB"mstr_standard"
BODY_TYPE"PLUMBING"
HDL_TAP"TRUE";
"B \NAC \NWC"1;
"S \NAC"
BN"6"155;
%"TAP"
"1","(-7825,4825)","2","mstr_standard","I80";
;
CDS_LIB"mstr_standard"
BODY_TYPE"PLUMBING"
HDL_TAP"TRUE";
"B \NAC \NWC"3;
"S \NAC"
BN"0"168;
%"TAP"
"1","(-7825,4875)","2","mstr_standard","I81";
;
CDS_LIB"mstr_standard"
BODY_TYPE"PLUMBING"
HDL_TAP"TRUE";
"B \NAC \NWC"3;
"S \NAC"
BN"1"166;
%"TAP"
"1","(-7825,4925)","2","mstr_standard","I82";
;
CDS_LIB"mstr_standard"
BODY_TYPE"PLUMBING"
HDL_TAP"TRUE";
"B \NAC \NWC"3;
"S \NAC"
BN"2"164;
%"TAP"
"1","(-7825,5025)","2","mstr_standard","I83";
;
CDS_LIB"mstr_standard"
BODY_TYPE"PLUMBING"
HDL_TAP"TRUE";
"B \NAC \NWC"3;
"S \NAC"
BN"4"160;
%"TAP"
"1","(-7825,4975)","2","mstr_standard","I84";
;
CDS_LIB"mstr_standard"
BODY_TYPE"PLUMBING"
HDL_TAP"TRUE";
"B \NAC \NWC"3;
"S \NAC"
BN"3"162;
%"TAP"
"1","(-7825,5075)","2","mstr_standard","I85";
;
CDS_LIB"mstr_standard"
BODY_TYPE"PLUMBING"
HDL_TAP"TRUE";
"B \NAC \NWC"3;
"S \NAC"
BN"5"158;
%"TAP"
"1","(-7825,5125)","2","mstr_standard","I86";
;
CDS_LIB"mstr_standard"
BODY_TYPE"PLUMBING"
HDL_TAP"TRUE";
"B \NAC \NWC"3;
"S \NAC"
BN"6"156;
%"TAP"
"1","(-7825,5225)","2","mstr_standard","I87";
;
CDS_LIB"mstr_standard"
BODY_TYPE"PLUMBING"
HDL_TAP"TRUE";
"B \NAC \NWC"2;
"S \NAC"
BN"0"169;
%"TAP"
"1","(-7825,5275)","2","mstr_standard","I88";
;
CDS_LIB"mstr_standard"
BODY_TYPE"PLUMBING"
HDL_TAP"TRUE";
"B \NAC \NWC"2;
"S \NAC"
BN"1"167;
%"TAP"
"1","(-7825,5325)","2","mstr_standard","I89";
;
CDS_LIB"mstr_standard"
BODY_TYPE"PLUMBING"
HDL_TAP"TRUE";
"B \NAC \NWC"2;
"S \NAC"
BN"2"165;
%"TAP"
"1","(-7825,5375)","2","mstr_standard","I90";
;
CDS_LIB"mstr_standard"
BODY_TYPE"PLUMBING"
HDL_TAP"TRUE";
"B \NAC \NWC"2;
"S \NAC"
BN"3"163;
%"TAP"
"1","(-7825,5425)","2","mstr_standard","I91";
;
CDS_LIB"mstr_standard"
BODY_TYPE"PLUMBING"
HDL_TAP"TRUE";
"B \NAC \NWC"2;
"S \NAC"
BN"4"161;
%"TAP"
"1","(-7825,5475)","2","mstr_standard","I92";
;
CDS_LIB"mstr_standard"
BODY_TYPE"PLUMBING"
HDL_TAP"TRUE";
"B \NAC \NWC"2;
"S \NAC"
BN"5"159;
%"TAP"
"1","(-7825,5525)","2","mstr_standard","I93";
;
CDS_LIB"mstr_standard"
BODY_TYPE"PLUMBING"
HDL_TAP"TRUE";
"B \NAC \NWC"2;
"S \NAC"
BN"6"157;
%"TAP"
"1","(-6125,3975)","0","mstr_standard","I94";
;
CDS_LIB"mstr_standard"
BODY_TYPE"PLUMBING"
HDL_TAP"TRUE";
"B \NAC \NWC"5;
"S \NAC"
BN"0"115;
%"TAP"
"1","(-6125,4025)","0","mstr_standard","I95";
;
CDS_LIB"mstr_standard"
BODY_TYPE"PLUMBING"
HDL_TAP"TRUE";
"B \NAC \NWC"5;
"S \NAC"
BN"1"116;
%"TAP"
"1","(-6125,4075)","0","mstr_standard","I96";
;
CDS_LIB"mstr_standard"
BODY_TYPE"PLUMBING"
HDL_TAP"TRUE";
"B \NAC \NWC"5;
"S \NAC"
BN"2"117;
%"TAP"
"1","(-6125,4125)","0","mstr_standard","I97";
;
CDS_LIB"mstr_standard"
BODY_TYPE"PLUMBING"
HDL_TAP"TRUE";
"B \NAC \NWC"5;
"S \NAC"
BN"3"118;
%"TAP"
"1","(-6125,4175)","0","mstr_standard","I98";
;
CDS_LIB"mstr_standard"
BODY_TYPE"PLUMBING"
HDL_TAP"TRUE";
"B \NAC \NWC"5;
"S \NAC"
BN"4"119;
%"TAP"
"1","(-6125,4225)","0","mstr_standard","I99";
;
CDS_LIB"mstr_standard"
BODY_TYPE"PLUMBING"
HDL_TAP"TRUE";
"B \NAC \NWC"5;
"S \NAC"
BN"5"120;
END.
